FILE_TYPE = CONNECTIVITY;
{Allegro Design Entry HDL 16.6-p007 (v16-6-112F) 10/10/2012}
"PAGE_NUMBER" = 83;
0"NC";
1"M_K_DQS_DP<17:0>";
2"M_K_DQS_DN<17:0>";
3"M_K_MA<17:0>";
4"M_K_DQ<63:0>";
5"M_K_CLK_DN<3:0>";
6"M_K_CLK_DP<3:0>";
7"M_K_BG<1:0>";
8"M_K_BA<1:0>";
9"M_K_CS_N<7:0>";
10"M_K_ECC<7:0>";
11"M_K_CKE<3:0>";
12"M_K_ODT<3:0>";
13"PVDDQ_KLM\g";
14"GND\g";
15"PVTT_KLM\g";
16"GND\g";
17"GND\g";
18"PVPP_KLM\g";
19"PVPP_KLM\g";
20"P12V_NVDIMM_KLM\g";
21"GND\g";
22"M_K_ALERT_N";
23"M_K_VREF";
24"TP_CH_K_DIMM_K0_RFU_1";
25"TP_CH_K_DIMM_K0_RFU_0";
26"TP_CH_K_DIMM_K0_RFU_2";
27"SMB_DDR_KLM_VPP_SDA";
28"SMB_DDR_KLM_VPP_SCL";
29"FM_ADR_COMPLETE_KLM_N";
30"FM_DIMM_EVENT_COD_N";
31"M_KLM_RST_N";
32"M_K_PAR";
33"M_K_C<2>";
34"M_K_CS_N<0>";
35"M_K_CKE<0>";
36"M_K_ODT<1>";
37"M_K_ODT<0>";
38"M_K_ECC<6>";
39"M_K_BA<0>";
40"M_K_BG<1>";
41"M_K_CKE<1>";
42"M_K_ECC<1>";
43"M_K_ECC<0>";
44"M_K_ECC<3>";
45"M_K_ECC<2>";
46"M_K_ECC<5>";
47"M_K_ECC<4>";
48"M_K_ECC<7>";
49"M_K_MA<1>";
50"M_K_MA<0>";
51"M_K_CS_N<1>";
52"M_K_CS_N<2>";
53"M_K_CS_N<3>";
54"M_K_BA<1>";
55"M_K_BG<0>";
56"M_K_CLK_DN<0>";
57"M_K_CLK_DP<0>";
58"M_K_CLK_DN<1>";
59"M_K_CLK_DP<1>";
60"M_K_ACT_N";
61"M_K_DQ<4>";
62"M_K_DQ<5>";
63"M_K_DQ<2>";
64"M_K_DQ<3>";
65"M_K_DQ<1>";
66"M_K_DQ<0>";
67"M_K_DQ<7>";
68"M_K_DQ<16>";
69"M_K_DQ<14>";
70"M_K_DQ<6>";
71"M_K_DQ<9>";
72"M_K_DQ<8>";
73"M_K_DQ<11>";
74"M_K_DQ<10>";
75"M_K_DQ<13>";
76"M_K_DQ<12>";
77"M_K_DQ<15>";
78"M_K_DQ<17>";
79"M_K_DQ<27>";
80"M_K_DQ<26>";
81"M_K_DQ<19>";
82"M_K_DQ<18>";
83"M_K_DQ<21>";
84"M_K_DQ<20>";
85"M_K_DQ<22>";
86"M_K_DQ<25>";
87"M_K_DQ<24>";
88"M_K_DQ<23>";
89"M_K_DQ<37>";
90"M_K_DQ<34>";
91"M_K_DQ<31>";
92"M_K_DQ<30>";
93"M_K_DQ<33>";
94"M_K_DQ<32>";
95"M_K_DQ<35>";
96"M_K_DQ<36>";
97"M_K_DQ<29>";
98"M_K_DQ<28>";
99"M_K_DQ<46>";
100"M_K_DQ<39>";
101"M_K_DQ<38>";
102"M_K_DQ<41>";
103"M_K_DQ<40>";
104"M_K_DQ<43>";
105"M_K_DQ<42>";
106"M_K_DQ<45>";
107"M_K_DQ<44>";
108"M_K_DQ<47>";
109"M_K_MA<16>";
110"M_K_MA<15>";
111"M_K_MA<14>";
112"M_K_MA<11>";
113"M_K_MA<10>";
114"M_K_MA<2>";
115"M_K_MA<9>";
116"M_K_MA<8>";
117"M_K_MA<7>";
118"M_K_MA<6>";
119"M_K_MA<5>";
120"M_K_MA<3>";
121"M_K_MA<17>";
122"M_K_MA<13>";
123"M_K_MA<12>";
124"M_K_MA<4>";
125"M_K_DQ<49>";
126"M_K_DQ<48>";
127"M_K_DQ<53>";
128"M_K_DQ<52>";
129"M_K_DQ<55>";
130"M_K_DQ<59>";
131"M_K_DQ<56>";
132"M_K_DQ<54>";
133"M_K_DQ<57>";
134"M_K_DQ<50>";
135"M_K_DQ<51>";
136"M_K_DQ<62>";
137"M_K_DQ<63>";
138"M_K_DQ<60>";
139"M_K_DQ<58>";
140"M_K_DQ<61>";
141"M_K_DQS_DN<6>";
142"M_K_DQS_DP<5>";
143"M_K_DQS_DN<5>";
144"M_K_DQS_DP<4>";
145"M_K_DQS_DN<4>";
146"M_K_DQS_DP<3>";
147"M_K_DQS_DN<3>";
148"M_K_DQS_DP<2>";
149"M_K_DQS_DN<2>";
150"M_K_DQS_DP<1>";
151"M_K_DQS_DN<1>";
152"M_K_DQS_DP<0>";
153"M_K_DQS_DN<0>";
154"M_K_DQS_DP<9>";
155"M_K_DQS_DN<9>";
156"M_K_DQS_DP<8>";
157"M_K_DQS_DN<8>";
158"M_K_DQS_DP<7>";
159"M_K_DQS_DN<7>";
160"M_K_DQS_DP<6>";
161"M_K_DQS_DP<16>";
162"M_K_DQS_DN<16>";
163"M_K_DQS_DP<15>";
164"M_K_DQS_DN<15>";
165"M_K_DQS_DP<14>";
166"M_K_DQS_DN<14>";
167"M_K_DQS_DP<13>";
168"M_K_DQS_DN<13>";
169"M_K_DQS_DP<12>";
170"M_K_DQS_DN<12>";
171"M_K_DQS_DP<11>";
172"M_K_DQS_DN<11>";
173"M_K_DQS_DP<10>";
174"M_K_DQS_DN<10>";
175"M_K_DQS_DP<17>";
176"M_K_DQS_DN<17>";
%"TAP"
"6","(700,4900)","2","mstr_standard","I10";
;
HDL_TAP"TRUE"
BODY_TYPE"PLUMBING"
CDS_LIB"mstr_standard";
"B \NAC \NWC"1;
"S \NAC"
BN"14"165;
%"TAP"
"6","(-1700,2150)","2","mstr_standard","I100";
;
HDL_TAP"TRUE"
BODY_TYPE"PLUMBING"
CDS_LIB"mstr_standard";
"B \NAC \NWC"4;
"S \NAC"
BN"8"72;
%"TAP"
"6","(-1700,2200)","2","mstr_standard","I101";
;
HDL_TAP"TRUE"
BODY_TYPE"PLUMBING"
CDS_LIB"mstr_standard";
"B \NAC \NWC"4;
"S \NAC"
BN"11"73;
%"TAP"
"6","(-1700,1900)","2","mstr_standard","I102";
;
HDL_TAP"TRUE"
BODY_TYPE"PLUMBING"
CDS_LIB"mstr_standard";
"B \NAC \NWC"4;
"S \NAC"
BN"5"62;
%"TAP"
"6","(-1700,1850)","2","mstr_standard","I103";
;
HDL_TAP"TRUE"
BODY_TYPE"PLUMBING"
CDS_LIB"mstr_standard";
"B \NAC \NWC"4;
"S \NAC"
BN"2"63;
%"TAP"
"6","(-1700,1950)","2","mstr_standard","I104";
;
HDL_TAP"TRUE"
BODY_TYPE"PLUMBING"
CDS_LIB"mstr_standard";
"B \NAC \NWC"4;
"S \NAC"
BN"4"61;
%"TAP"
"6","(-1700,2000)","2","mstr_standard","I105";
;
HDL_TAP"TRUE"
BODY_TYPE"PLUMBING"
CDS_LIB"mstr_standard";
"B \NAC \NWC"4;
"S \NAC"
BN"7"67;
%"TAP"
"6","(-1700,2100)","2","mstr_standard","I106";
;
HDL_TAP"TRUE"
BODY_TYPE"PLUMBING"
CDS_LIB"mstr_standard";
"B \NAC \NWC"4;
"S \NAC"
BN"9"71;
%"TAP"
"6","(-1700,2050)","2","mstr_standard","I107";
;
HDL_TAP"TRUE"
BODY_TYPE"PLUMBING"
CDS_LIB"mstr_standard";
"B \NAC \NWC"4;
"S \NAC"
BN"6"70;
%"TAP"
"6","(-1700,1700)","2","mstr_standard","I108";
;
HDL_TAP"TRUE"
BODY_TYPE"PLUMBING"
CDS_LIB"mstr_standard";
"B \NAC \NWC"4;
"S \NAC"
BN"1"65;
%"TAP"
"6","(-1700,1800)","2","mstr_standard","I109";
;
HDL_TAP"TRUE"
BODY_TYPE"PLUMBING"
CDS_LIB"mstr_standard";
"B \NAC \NWC"4;
"S \NAC"
BN"3"64;
%"TAP"
"6","(700,5000)","2","mstr_standard","I11";
;
HDL_TAP"TRUE"
BODY_TYPE"PLUMBING"
CDS_LIB"mstr_standard";
"B \NAC \NWC"1;
"S \NAC"
BN"15"163;
%"TAP"
"6","(-1700,1750)","2","mstr_standard","I110";
;
HDL_TAP"TRUE"
BODY_TYPE"PLUMBING"
CDS_LIB"mstr_standard";
"B \NAC \NWC"4;
"S \NAC"
BN"0"66;
%"SCONN288_H44441004"
"1","(-2450,3200)","0","mstr_sconn","I111";
;
CDS_SEC"1"
ROOM"DDR4_CH_K"
CDS_LOCATION"J1B1"
SEC"1"
SEC_TYPE"PIP"
CDS_LIB"mstr_sconn"
BOM_COST"MEM"
PACK_TYPE"PIP"
MATERIAL"SCONN"
PART_NUMBER"H44441-004"
LOCATION"J1B1";
"DQ<63>"
$PN"280"136;
"DQ<62>"
$PN"135"137;
"DQ<61>"
$PN"273"138;
"DQ<5>"
$PN"148"61;
"DQ<4>"
$PN"3"62;
"DQ<3>"
$PN"157"63;
"DQ<2>"
$PN"12"64;
"DQ<47>"
$PN"258"99;
"DQ<48>"
$PN"119"125;
"DQ<49>"
$PN"264"126;
"DQ<50>"
$PN"126"135;
"DQ<51>"
$PN"271"134;
"DQ<52>"
$PN"117"127;
"DQ<53>"
$PN"262"128;
"DQ<54>"
$PN"124"129;
"DQ<58>"
$PN"137"130;
"DQ<57>"
$PN"275"131;
"SAVE_N_NC"
$PN"230"29;
"RFU<1>"
$PN"227"24;
"RFU<0>"
$PN"205"25;
"DQ<17>"
$PN"172"68;
"DQ<15>"
$PN"166"69;
"DQ<26>"
$PN"45"79;
"DQ<27>"
$PN"190"80;
"S0_N"
$PN"84"34;
"CKE<0>"
$PN"60"35;
"ODT<1>"
$PN"91"36;
"ODT<0>"
$PN"87"37;
"CB<7>"
$PN"199"38;
"A16_RAS_N"
$PN"82"109;
"A15_CAS_N"
$PN"86"110;
"A14_WE_N"
$PN"228"111;
"A11"
$PN"210"112;
"A10"
$PN"225"113;
"DQ<38>"
$PN"102"100;
"DQ<36>"
$PN"95"89;
"DQ<35>"
$PN"249"90;
"A2"
$PN"216"114;
"ALERT_N"
$PN"208"22;
"ACT_N"
$PN"62"60;
"DQ<0>"
$PN"5"65;
"DQ<1>"
$PN"150"66;
"SA<1>"
$PN"140"16;
"SA<2>"
$PN"238"16;
"VDDSPD"
$PN"284"19;
"SA<0>"
$PN"139"16;
"BA<0>"
$PN"81"39;
"BG<1>"
$PN"207"40;
"BG<0>"
$PN"63"55;
"CK1P"
$PN"218"59;
"VREFCA"
$PN"146"23;
"SDA"
$PN"285"27;
"SCL"
$PN"141"28;
"RFU<2>"
$PN"144"26;
"RESET_N"
$PN"58"31;
"PAR"
$PN"222"32;
"EVENT_N"
$PN"78"30;
"DQ<6>"
$PN"10"67;
"DQ<7>"
$PN"155"70;
"DQ<8>"
$PN"16"71;
"DQ<9>"
$PN"161"72;
"DQ<10>"
$PN"23"73;
"DQ<11>"
$PN"168"74;
"DQ<12>"
$PN"14"75;
"DQ<13>"
$PN"159"76;
"DQ<14>"
$PN"21"77;
"DQ<16>"
$PN"27"78;
"DQ<18>"
$PN"34"81;
"DQ<19>"
$PN"179"82;
"DQ<20>"
$PN"25"83;
"DQ<21>"
$PN"170"84;
"DQ<22>"
$PN"32"88;
"DQ<23>"
$PN"177"85;
"DQ<24>"
$PN"38"86;
"DQ<25>"
$PN"183"87;
"DQ<30>"
$PN"43"91;
"DQ<31>"
$PN"188"92;
"DQ<32>"
$PN"97"93;
"DQ<33>"
$PN"242"94;
"DQ<34>"
$PN"104"95;
"DQ<37>"
$PN"240"96;
"DQ<39>"
$PN"247"101;
"DQ<40>"
$PN"108"102;
"DQ<41>"
$PN"253"103;
"DQ<42>"
$PN"115"104;
"DQ<43>"
$PN"260"105;
"DQ<44>"
$PN"106"106;
"DQ<45>"
$PN"251"107;
"DQ<46>"
$PN"113"108;
"DQ<55>"
$PN"269"132;
"DQ<56>"
$PN"130"133;
"DQ<59>"
$PN"282"139;
"DQ<60>"
$PN"128"140;
"CKE<1>"
$PN"203"41;
"CK0N"
$PN"75"56;
"CB<0>"
$PN"49"42;
"CB<1>"
$PN"194"43;
"CB<2>"
$PN"56"44;
"CB<3>"
$PN"201"45;
"CB<4>"
$PN"47"46;
"CB<5>"
$PN"192"47;
"CB<6>"
$PN"54"48;
"A9"
$PN"66"115;
"A8"
$PN"68"116;
"A7"
$PN"211"117;
"A6"
$PN"69"118;
"A5"
$PN"213"119;
"A4"
$PN"214"124;
"A3"
$PN"71"120;
"A17"
$PN"234"121;
"A13"
$PN"232"122;
"A12"
$PN"65"123;
"A1"
$PN"72"49;
"A0"
$PN"79"50;
"C<2>"
$PN"235"33;
"DQ<28>"
$PN"36"97;
"DQ<29>"
$PN"181"98;
"S1_N"
$PN"89"51;
"S2_N_C<0>"
$PN"93"52;
"S3_N_C<1>"
$PN"237"53;
"CK0P"
$PN"74"57;
"CK1N"
$PN"219"58;
"BA<1>"
$PN"224"54;
%"TAP"
"6","(-3200,4800)","0","mstr_standard","I112";
;
HDL_TAP"TRUE"
BODY_TYPE"PLUMBING"
CDS_LIB"mstr_standard";
"B \NAC \NWC"3;
"S \NAC"
BN"16"109;
%"TAP"
"6","(-3200,4850)","0","mstr_standard","I113";
;
HDL_TAP"TRUE"
BODY_TYPE"PLUMBING"
CDS_LIB"mstr_standard";
"B \NAC \NWC"3;
"S \NAC"
BN"17"121;
%"TAP"
"6","(-3200,4750)","0","mstr_standard","I114";
;
HDL_TAP"TRUE"
BODY_TYPE"PLUMBING"
CDS_LIB"mstr_standard";
"B \NAC \NWC"3;
"S \NAC"
BN"15"110;
%"TAP"
"6","(-3200,4700)","0","mstr_standard","I115";
;
HDL_TAP"TRUE"
BODY_TYPE"PLUMBING"
CDS_LIB"mstr_standard";
"B \NAC \NWC"3;
"S \NAC"
BN"14"111;
%"TAP"
"6","(-3200,4650)","0","mstr_standard","I116";
;
HDL_TAP"TRUE"
BODY_TYPE"PLUMBING"
CDS_LIB"mstr_standard";
"B \NAC \NWC"3;
"S \NAC"
BN"13"122;
%"TAP"
"6","(-3200,4600)","0","mstr_standard","I117";
;
HDL_TAP"TRUE"
BODY_TYPE"PLUMBING"
CDS_LIB"mstr_standard";
"B \NAC \NWC"3;
"S \NAC"
BN"12"123;
%"TAP"
"6","(-3200,4550)","0","mstr_standard","I118";
;
HDL_TAP"TRUE"
BODY_TYPE"PLUMBING"
CDS_LIB"mstr_standard";
"B \NAC \NWC"3;
"S \NAC"
BN"11"112;
%"TAP"
"6","(-3200,4500)","0","mstr_standard","I119";
;
HDL_TAP"TRUE"
BODY_TYPE"PLUMBING"
CDS_LIB"mstr_standard";
"B \NAC \NWC"3;
"S \NAC"
BN"10"113;
%"TAP"
"6","(700,5100)","2","mstr_standard","I12";
;
HDL_TAP"TRUE"
BODY_TYPE"PLUMBING"
CDS_LIB"mstr_standard";
"B \NAC \NWC"1;
"S \NAC"
BN"16"161;
%"TAP"
"6","(-3200,4450)","0","mstr_standard","I120";
;
HDL_TAP"TRUE"
BODY_TYPE"PLUMBING"
CDS_LIB"mstr_standard";
"B \NAC \NWC"3;
"S \NAC"
BN"9"115;
%"TAP"
"6","(-3200,4400)","0","mstr_standard","I121";
;
HDL_TAP"TRUE"
BODY_TYPE"PLUMBING"
CDS_LIB"mstr_standard";
"B \NAC \NWC"3;
"S \NAC"
BN"8"116;
%"TAP"
"6","(-3200,4350)","0","mstr_standard","I122";
;
HDL_TAP"TRUE"
BODY_TYPE"PLUMBING"
CDS_LIB"mstr_standard";
"B \NAC \NWC"3;
"S \NAC"
BN"7"117;
%"TAP"
"6","(-3200,4300)","0","mstr_standard","I123";
;
HDL_TAP"TRUE"
BODY_TYPE"PLUMBING"
CDS_LIB"mstr_standard";
"B \NAC \NWC"3;
"S \NAC"
BN"6"118;
%"TAP"
"6","(-3200,4250)","0","mstr_standard","I124";
;
HDL_TAP"TRUE"
BODY_TYPE"PLUMBING"
CDS_LIB"mstr_standard";
"B \NAC \NWC"3;
"S \NAC"
BN"5"119;
%"TAP"
"6","(-3200,4200)","0","mstr_standard","I125";
;
HDL_TAP"TRUE"
BODY_TYPE"PLUMBING"
CDS_LIB"mstr_standard";
"B \NAC \NWC"3;
"S \NAC"
BN"4"124;
%"TAP"
"6","(-3200,4100)","0","mstr_standard","I126";
;
HDL_TAP"TRUE"
BODY_TYPE"PLUMBING"
CDS_LIB"mstr_standard";
"B \NAC \NWC"3;
"S \NAC"
BN"2"114;
%"TAP"
"6","(-3200,4150)","0","mstr_standard","I127";
;
HDL_TAP"TRUE"
BODY_TYPE"PLUMBING"
CDS_LIB"mstr_standard";
"B \NAC \NWC"3;
"S \NAC"
BN"3"120;
%"TAP"
"6","(-3200,4050)","0","mstr_standard","I128";
;
HDL_TAP"TRUE"
BODY_TYPE"PLUMBING"
CDS_LIB"mstr_standard";
"B \NAC \NWC"3;
"S \NAC"
BN"1"49;
%"TAP"
"6","(-3200,4000)","0","mstr_standard","I129";
;
HDL_TAP"TRUE"
BODY_TYPE"PLUMBING"
CDS_LIB"mstr_standard";
"B \NAC \NWC"3;
"S \NAC"
BN"0"50;
%"TAP"
"6","(700,4600)","2","mstr_standard","I13";
;
HDL_TAP"TRUE"
BODY_TYPE"PLUMBING"
CDS_LIB"mstr_standard";
"B \NAC \NWC"1;
"S \NAC"
BN"11"171;
%"TAP"
"6","(-3200,3900)","0","mstr_standard","I130";
;
HDL_TAP"TRUE"
BODY_TYPE"PLUMBING"
CDS_LIB"mstr_standard";
"B \NAC \NWC"8;
"S \NAC"
BN"1"54;
%"TAP"
"6","(-3200,3850)","0","mstr_standard","I133";
;
HDL_TAP"TRUE"
BODY_TYPE"PLUMBING"
CDS_LIB"mstr_standard";
"B \NAC \NWC"8;
"S \NAC"
BN"0"39;
%"TAP"
"6","(-3200,3800)","0","mstr_standard","I134";
;
HDL_TAP"TRUE"
BODY_TYPE"PLUMBING"
CDS_LIB"mstr_standard";
"B \NAC \NWC"7;
"S \NAC"
BN"1"40;
%"TAP"
"6","(-3200,3750)","0","mstr_standard","I135";
;
HDL_TAP"TRUE"
BODY_TYPE"PLUMBING"
CDS_LIB"mstr_standard";
"B \NAC \NWC"7;
"S \NAC"
BN"0"55;
%"TAP"
"6","(-3200,2800)","0","mstr_standard","I138";
;
HDL_TAP"TRUE"
BODY_TYPE"PLUMBING"
CDS_LIB"mstr_standard";
"B \NAC \NWC"10;
"S \NAC"
BN"6"38;
%"TAP"
"6","(-3200,2750)","0","mstr_standard","I139";
;
HDL_TAP"TRUE"
BODY_TYPE"PLUMBING"
CDS_LIB"mstr_standard";
"B \NAC \NWC"10;
"S \NAC"
BN"7"48;
%"TAP"
"6","(700,4700)","2","mstr_standard","I14";
;
HDL_TAP"TRUE"
BODY_TYPE"PLUMBING"
CDS_LIB"mstr_standard";
"B \NAC \NWC"1;
"S \NAC"
BN"12"169;
%"TAP"
"6","(-3200,2700)","0","mstr_standard","I140";
;
HDL_TAP"TRUE"
BODY_TYPE"PLUMBING"
CDS_LIB"mstr_standard";
"B \NAC \NWC"10;
"S \NAC"
BN"4"47;
%"TAP"
"6","(-3200,2650)","0","mstr_standard","I141";
;
HDL_TAP"TRUE"
BODY_TYPE"PLUMBING"
CDS_LIB"mstr_standard";
"B \NAC \NWC"10;
"S \NAC"
BN"5"46;
%"TAP"
"6","(-3200,2600)","0","mstr_standard","I142";
;
HDL_TAP"TRUE"
BODY_TYPE"PLUMBING"
CDS_LIB"mstr_standard";
"B \NAC \NWC"10;
"S \NAC"
BN"2"45;
%"TAP"
"6","(-3200,2550)","0","mstr_standard","I143";
;
HDL_TAP"TRUE"
BODY_TYPE"PLUMBING"
CDS_LIB"mstr_standard";
"B \NAC \NWC"10;
"S \NAC"
BN"3"44;
%"TAP"
"6","(-3200,2500)","0","mstr_standard","I144";
;
HDL_TAP"TRUE"
BODY_TYPE"PLUMBING"
CDS_LIB"mstr_standard";
"B \NAC \NWC"10;
"S \NAC"
BN"0"43;
%"TAP"
"6","(-3200,2450)","0","mstr_standard","I145";
;
HDL_TAP"TRUE"
BODY_TYPE"PLUMBING"
CDS_LIB"mstr_standard";
"B \NAC \NWC"10;
"S \NAC"
BN"1"42;
%"TAP"
"6","(700,4800)","2","mstr_standard","I15";
;
HDL_TAP"TRUE"
BODY_TYPE"PLUMBING"
CDS_LIB"mstr_standard";
"B \NAC \NWC"1;
"S \NAC"
BN"13"167;
%"TAP"
"6","(-3200,3350)","0","mstr_standard","I152";
;
HDL_TAP"TRUE"
BODY_TYPE"PLUMBING"
CDS_LIB"mstr_standard";
"B \NAC \NWC"9;
"S \NAC"
BN"3"53;
%"TAP"
"6","(-3200,3300)","0","mstr_standard","I153";
;
HDL_TAP"TRUE"
BODY_TYPE"PLUMBING"
CDS_LIB"mstr_standard";
"B \NAC \NWC"9;
"S \NAC"
BN"2"52;
%"TAP"
"6","(-3200,3050)","0","mstr_standard","I154";
;
HDL_TAP"TRUE"
BODY_TYPE"PLUMBING"
CDS_LIB"mstr_standard";
"B \NAC \NWC"11;
"S \NAC"
BN"0"35;
%"TAP"
"6","(-3200,2900)","0","mstr_standard","I155";
;
HDL_TAP"TRUE"
BODY_TYPE"PLUMBING"
CDS_LIB"mstr_standard";
"B \NAC \NWC"12;
"S \NAC"
BN"0"37;
%"TAP"
"6","(-3550,3550)","0","mstr_standard","I156";
;
HDL_TAP"TRUE"
BODY_TYPE"PLUMBING"
CDS_LIB"mstr_standard";
"B \NAC \NWC"6;
"S \NAC"
BN"0"57;
%"TAP"
"6","(-3700,3500)","0","mstr_standard","I159";
;
HDL_TAP"TRUE"
BODY_TYPE"PLUMBING"
CDS_LIB"mstr_standard";
"B \NAC \NWC"5;
"S \NAC"
BN"0"56;
%"PVDDQ_KLM"
"1","(-1300,2625)","0","mstr_symbols","I16";
;
HDL_POWER"PVDDQ_KLM"
ROOM"DDR4_CH_C"
BODY_TYPE"PLUMBING"
CDS_LIB"mstr_symbols"
BOM_COST"MEM"
VOLTAGE"1.2V";
"G\NAC"13;
%"TAP"
"6","(-3200,3250)","0","mstr_standard","I163";
;
HDL_TAP"TRUE"
BODY_TYPE"PLUMBING"
CDS_LIB"mstr_standard";
"B \NAC \NWC"9;
"S \NAC"
BN"1"51;
%"TAP"
"6","(-3200,3200)","0","mstr_standard","I164";
;
HDL_TAP"TRUE"
BODY_TYPE"PLUMBING"
CDS_LIB"mstr_standard";
"B \NAC \NWC"9;
"S \NAC"
BN"0"34;
%"TAP"
"6","(-3200,3100)","0","mstr_standard","I165";
;
HDL_TAP"TRUE"
BODY_TYPE"PLUMBING"
CDS_LIB"mstr_standard";
"B \NAC \NWC"11;
"S \NAC"
BN"1"41;
%"TAP"
"6","(-3200,2950)","0","mstr_standard","I166";
;
HDL_TAP"TRUE"
BODY_TYPE"PLUMBING"
CDS_LIB"mstr_standard";
"B \NAC \NWC"12;
"S \NAC"
BN"1"36;
%"SCONN288_H44441004"
"4","(-150,2100)","0","mstr_sconn","I167";
;
CDS_SEC"4"
ROOM"DDR4_CH_K"
CDS_LOCATION"J1B1"
SEC"4"
SEC_TYPE"PIP"
CDS_LIB"mstr_sconn"
BOM_COST"MEM"
PACK_TYPE"PIP"
MATERIAL"SCONN"
PART_NUMBER"H44441-004"
LOCATION"J1B1";
"VPP<4>"
$PN"142"18;
"VTT<1>"
$PN"77"15;
"VPP<0>"
$PN"287"18;
"VPP<1>"
$PN"286"18;
"VPP<2>"
$PN"288"18;
"VPP<3>"
$PN"143"18;
"VDD<1>"
$PN"233"13;
"VDD<2>"
$PN"231"13;
"VDD<3>"
$PN"229"13;
"VDD<4>"
$PN"226"13;
"VDD<5>"
$PN"223"13;
"VDD<7>"
$PN"217"13;
"VDD<8>"
$PN"215"13;
"VDD<9>"
$PN"212"13;
"VDD<11>"
$PN"206"13;
"VDD<12>"
$PN"204"13;
"VDD<14>"
$PN"90"13;
"VDD<15>"
$PN"88"13;
"VDD<17>"
$PN"83"13;
"VDD<18>"
$PN"80"13;
"VDD<20>"
$PN"73"13;
"VDD<21>"
$PN"70"13;
"VDD<22>"
$PN"67"13;
"VDD<24>"
$PN"61"13;
"12V<0>"
$PN"145"20;
"12V<1>"
$PN"1"20;
"VTT<0>"
$PN"221"15;
"VDD<25>"
$PN"59"13;
"VDD<23>"
$PN"64"13;
"VDD<19>"
$PN"76"13;
"VDD<16>"
$PN"85"13;
"VDD<13>"
$PN"92"13;
"VDD<10>"
$PN"209"13;
"VDD<6>"
$PN"220"13;
"VDD<0>"
$PN"236"13;
%"GND"
"1","(2500,1100)","2","mstr_symbols","I168";
;
HDL_POWER"GND"
ROOM"DDR4_CH_C"
BODY_TYPE"PLUMBING"
CDS_LIB"mstr_symbols"
SIZE"1B"
BOM_COST"MEM"
VOLTAGE"0";
"A\NAC"14;
%"PVTT_KLM"
"1","(-1050,2800)","0","mstr_symbols","I17";
;
HDL_POWER"PVTT_KLM"
ROOM"DDR4_CH_C"
BODY_TYPE"PLUMBING"
CDS_LIB"mstr_symbols"
BOM_COST"MEM"
VOLTAGE"0.6V";
"G\NAC"15;
%"GND"
"1","(-5100,1850)","2","mstr_symbols","I173";
;
HDL_POWER"GND"
ROOM"DDR4_CH_C"
BODY_TYPE"PLUMBING"
SIZE"1B"
CDS_LIB"mstr_symbols"
BOM_COST"MEM"
VOLTAGE"0";
"A\NAC"16;
%"GND"
"1","(-4600,1250)","0","mstr_symbols","I175";
;
HDL_POWER"GND"
ROOM"DDR4_CH_C"
BODY_TYPE"PLUMBING"
CDS_LIB"mstr_symbols"
SIZE"1B"
BOM_COST"MEM"
VOLTAGE"0";
"A\NAC"17;
%"CAP_A"
"1","(-4600,1500)","2","dev_discrete","I176";
;
ROOM"DDR4_CH_K"
$SEC"1"
CDS_SEC"1"
CDS_LIB"dev_discrete"
BOM_COST"MEM"
CDS_LOCATION"C1B9"
MATERIAL"X7R"
VOLTAGE"25V"
PACK_TYPE"0402V"
TOLERANCE"10%"
VALUE"0.01UF"
PART_NUMBER"A36096-045"
LOCATION"C1B9";
"B"
$PN"2"17;
"A"
$PN"1"23;
%"PVPP_KLM"
"1","(-850,3100)","0","mstr_symbols","I177";
;
HDL_POWER"PVPP_KLM"
ROOM"DDR4_CH_C"
BODY_TYPE"PLUMBING"
CDS_LIB"mstr_symbols"
BOM_COST"MEM"
VOLTAGE"2.5V";
"G\NAC"18;
%"PVPP_KLM"
"1","(-5100,2200)","0","mstr_symbols","I178";
;
HDL_POWER"PVPP_KLM"
ROOM"DDR4_CH_C"
BODY_TYPE"PLUMBING"
CDS_LIB"mstr_symbols"
BOM_COST"MEM"
VOLTAGE"2.5V";
"G\NAC"19;
%"TAP"
"6","(-3700,3600)","0","mstr_standard","I183";
;
HDL_TAP"TRUE"
BODY_TYPE"PLUMBING"
CDS_LIB"mstr_standard";
"B \NAC \NWC"5;
"S \NAC"
BN"1"58;
%"TAP"
"6","(-3550,3650)","0","mstr_standard","I184";
;
HDL_TAP"TRUE"
BODY_TYPE"PLUMBING"
CDS_LIB"mstr_standard";
"B \NAC \NWC"6;
"S \NAC"
BN"1"59;
%"P12V_NVDIMM_KLM"
"1","(550,3175)","0","mstr_symbols","I185";
;
HDL_POWER"P12V_NVDIMM_KLM"
BODY_TYPE"PLUMBING"
CDS_LIB"mstr_symbols"
VOLTAGE"12.0";
"G\NAC"20;
%"TAP"
"6","(900,4550)","2","mstr_standard","I19";
;
HDL_TAP"TRUE"
BODY_TYPE"PLUMBING"
CDS_LIB"mstr_standard";
"B \NAC \NWC"2;
"S \NAC"
BN"11"172;
%"TAP"
"6","(900,4450)","2","mstr_standard","I20";
;
HDL_TAP"TRUE"
BODY_TYPE"PLUMBING"
CDS_LIB"mstr_standard";
"B \NAC \NWC"2;
"S \NAC"
BN"10"174;
%"TAP"
"6","(900,4350)","2","mstr_standard","I21";
;
HDL_TAP"TRUE"
BODY_TYPE"PLUMBING"
CDS_LIB"mstr_standard";
"B \NAC \NWC"2;
"S \NAC"
BN"9"155;
%"TAP"
"6","(900,4250)","2","mstr_standard","I22";
;
HDL_TAP"TRUE"
BODY_TYPE"PLUMBING"
CDS_LIB"mstr_standard";
"B \NAC \NWC"2;
"S \NAC"
BN"8"157;
%"TAP"
"6","(900,4150)","2","mstr_standard","I23";
;
HDL_TAP"TRUE"
BODY_TYPE"PLUMBING"
CDS_LIB"mstr_standard";
"B \NAC \NWC"2;
"S \NAC"
BN"7"159;
%"TAP"
"6","(700,4500)","2","mstr_standard","I24";
;
HDL_TAP"TRUE"
BODY_TYPE"PLUMBING"
CDS_LIB"mstr_standard";
"B \NAC \NWC"1;
"S \NAC"
BN"10"173;
%"TAP"
"6","(700,4400)","2","mstr_standard","I25";
;
HDL_TAP"TRUE"
BODY_TYPE"PLUMBING"
CDS_LIB"mstr_standard";
"B \NAC \NWC"1;
"S \NAC"
BN"9"154;
%"TAP"
"6","(700,4100)","2","mstr_standard","I26";
;
HDL_TAP"TRUE"
BODY_TYPE"PLUMBING"
CDS_LIB"mstr_standard";
"B \NAC \NWC"1;
"S \NAC"
BN"6"160;
%"TAP"
"6","(700,4200)","2","mstr_standard","I27";
;
HDL_TAP"TRUE"
BODY_TYPE"PLUMBING"
CDS_LIB"mstr_standard";
"B \NAC \NWC"1;
"S \NAC"
BN"7"158;
%"TAP"
"6","(700,4300)","2","mstr_standard","I28";
;
HDL_TAP"TRUE"
BODY_TYPE"PLUMBING"
CDS_LIB"mstr_standard";
"B \NAC \NWC"1;
"S \NAC"
BN"8"156;
%"TAP"
"6","(900,4050)","2","mstr_standard","I29";
;
HDL_TAP"TRUE"
BODY_TYPE"PLUMBING"
CDS_LIB"mstr_standard";
"B \NAC \NWC"2;
"S \NAC"
BN"6"141;
%"TAP"
"6","(900,5150)","2","mstr_standard","I3";
;
HDL_TAP"TRUE"
BODY_TYPE"PLUMBING"
CDS_LIB"mstr_standard";
"B \NAC \NWC"2;
"S \NAC"
BN"17"176;
%"TAP"
"6","(900,3950)","2","mstr_standard","I30";
;
HDL_TAP"TRUE"
BODY_TYPE"PLUMBING"
CDS_LIB"mstr_standard";
"B \NAC \NWC"2;
"S \NAC"
BN"5"143;
%"TAP"
"6","(900,3850)","2","mstr_standard","I31";
;
HDL_TAP"TRUE"
BODY_TYPE"PLUMBING"
CDS_LIB"mstr_standard";
"B \NAC \NWC"2;
"S \NAC"
BN"4"145;
%"TAP"
"6","(900,3750)","2","mstr_standard","I32";
;
HDL_TAP"TRUE"
BODY_TYPE"PLUMBING"
CDS_LIB"mstr_standard";
"B \NAC \NWC"2;
"S \NAC"
BN"3"147;
%"TAP"
"6","(900,3650)","2","mstr_standard","I33";
;
HDL_TAP"TRUE"
BODY_TYPE"PLUMBING"
CDS_LIB"mstr_standard";
"B \NAC \NWC"2;
"S \NAC"
BN"2"149;
%"TAP"
"6","(700,4000)","2","mstr_standard","I34";
;
HDL_TAP"TRUE"
BODY_TYPE"PLUMBING"
CDS_LIB"mstr_standard";
"B \NAC \NWC"1;
"S \NAC"
BN"5"142;
%"TAP"
"6","(700,3900)","2","mstr_standard","I35";
;
HDL_TAP"TRUE"
BODY_TYPE"PLUMBING"
CDS_LIB"mstr_standard";
"B \NAC \NWC"1;
"S \NAC"
BN"4"144;
%"TAP"
"6","(700,3700)","2","mstr_standard","I36";
;
HDL_TAP"TRUE"
BODY_TYPE"PLUMBING"
CDS_LIB"mstr_standard";
"B \NAC \NWC"1;
"S \NAC"
BN"2"148;
%"TAP"
"6","(700,3600)","2","mstr_standard","I37";
;
HDL_TAP"TRUE"
BODY_TYPE"PLUMBING"
CDS_LIB"mstr_standard";
"B \NAC \NWC"1;
"S \NAC"
BN"1"150;
%"TAP"
"6","(700,3800)","2","mstr_standard","I38";
;
HDL_TAP"TRUE"
BODY_TYPE"PLUMBING"
CDS_LIB"mstr_standard";
"B \NAC \NWC"1;
"S \NAC"
BN"3"146;
%"TAP"
"6","(900,3450)","2","mstr_standard","I39";
;
HDL_TAP"TRUE"
BODY_TYPE"PLUMBING"
CDS_LIB"mstr_standard";
"B \NAC \NWC"2;
"S \NAC"
BN"0"153;
%"TAP"
"6","(700,5200)","2","mstr_standard","I4";
;
HDL_TAP"TRUE"
BODY_TYPE"PLUMBING"
CDS_LIB"mstr_standard";
"B \NAC \NWC"1;
"S \NAC"
BN"17"175;
%"TAP"
"6","(900,3550)","2","mstr_standard","I40";
;
HDL_TAP"TRUE"
BODY_TYPE"PLUMBING"
CDS_LIB"mstr_standard";
"B \NAC \NWC"2;
"S \NAC"
BN"1"151;
%"TAP"
"6","(700,3500)","2","mstr_standard","I41";
;
HDL_TAP"TRUE"
BODY_TYPE"PLUMBING"
CDS_LIB"mstr_standard";
"B \NAC \NWC"1;
"S \NAC"
BN"0"152;
%"SCONN288_H44441004"
"3","(1800,2400)","0","mstr_sconn","I43";
;
CDS_SEC"3"
ROOM"DDR4_CH_K"
CDS_LOCATION"J1B1"
SEC"3"
SEC_TYPE"PIP"
CDS_LIB"mstr_sconn"
BOM_COST"MEM"
PACK_TYPE"PIP"
MATERIAL"SCONN"
PART_NUMBER"H44441-004"
LOCATION"J1B1";
"VSS<93>"
$PN"2"21;
"VSS<92>"
$PN"4"21;
"VSS<91>"
$PN"6"21;
"VSS<90>"
$PN"9"21;
"VSS<89>"
$PN"11"21;
"VSS<88>"
$PN"13"21;
"VSS<0>"
$PN"283"14;
"VSS<1>"
$PN"281"14;
"VSS<2>"
$PN"279"14;
"VSS<3>"
$PN"276"14;
"VSS<4>"
$PN"274"14;
"VSS<5>"
$PN"272"14;
"VSS<6>"
$PN"270"14;
"VSS<7>"
$PN"268"14;
"VSS<8>"
$PN"265"14;
"VSS<9>"
$PN"263"14;
"VSS<10>"
$PN"261"14;
"VSS<11>"
$PN"259"14;
"VSS<12>"
$PN"257"14;
"VSS<13>"
$PN"254"14;
"VSS<14>"
$PN"252"14;
"VSS<15>"
$PN"250"14;
"VSS<16>"
$PN"248"14;
"VSS<17>"
$PN"246"14;
"VSS<18>"
$PN"243"14;
"VSS<19>"
$PN"241"14;
"VSS<20>"
$PN"239"14;
"VSS<21>"
$PN"202"14;
"VSS<22>"
$PN"200"14;
"VSS<23>"
$PN"198"14;
"VSS<24>"
$PN"195"14;
"VSS<25>"
$PN"193"14;
"VSS<26>"
$PN"191"14;
"VSS<27>"
$PN"189"14;
"VSS<28>"
$PN"187"14;
"VSS<29>"
$PN"184"14;
"VSS<30>"
$PN"182"14;
"VSS<31>"
$PN"180"14;
"VSS<32>"
$PN"178"14;
"VSS<33>"
$PN"176"14;
"VSS<34>"
$PN"173"14;
"VSS<35>"
$PN"171"14;
"VSS<36>"
$PN"169"14;
"VSS<37>"
$PN"167"14;
"VSS<38>"
$PN"165"14;
"VSS<39>"
$PN"162"14;
"VSS<40>"
$PN"160"14;
"VSS<41>"
$PN"158"14;
"VSS<42>"
$PN"156"14;
"VSS<43>"
$PN"154"14;
"VSS<44>"
$PN"151"14;
"VSS<47>"
$PN"138"21;
"VSS<48>"
$PN"136"21;
"VSS<49>"
$PN"134"21;
"VSS<50>"
$PN"131"21;
"VSS<51>"
$PN"129"21;
"VSS<52>"
$PN"127"21;
"VSS<53>"
$PN"125"21;
"VSS<54>"
$PN"123"21;
"VSS<55>"
$PN"120"21;
"VSS<56>"
$PN"118"21;
"VSS<57>"
$PN"116"21;
"VSS<58>"
$PN"114"21;
"VSS<59>"
$PN"112"21;
"VSS<60>"
$PN"109"21;
"VSS<61>"
$PN"107"21;
"VSS<62>"
$PN"105"21;
"VSS<63>"
$PN"103"21;
"VSS<64>"
$PN"101"21;
"VSS<65>"
$PN"98"21;
"VSS<66>"
$PN"96"21;
"VSS<67>"
$PN"94"21;
"VSS<68>"
$PN"57"21;
"VSS<69>"
$PN"55"21;
"VSS<70>"
$PN"53"21;
"VSS<71>"
$PN"50"21;
"VSS<72>"
$PN"48"21;
"VSS<73>"
$PN"46"21;
"VSS<74>"
$PN"44"21;
"VSS<75>"
$PN"42"21;
"VSS<76>"
$PN"39"21;
"VSS<77>"
$PN"37"21;
"VSS<78>"
$PN"35"21;
"VSS<79>"
$PN"33"21;
"VSS<80>"
$PN"31"21;
"VSS<81>"
$PN"28"21;
"VSS<82>"
$PN"26"21;
"VSS<83>"
$PN"24"21;
"VSS<84>"
$PN"22"21;
"VSS<85>"
$PN"20"21;
"VSS<86>"
$PN"17"21;
"VSS<87>"
$PN"15"21;
"VSS<45>"
$PN"149"14;
"VSS<46>"
$PN"147"14;
%"GND"
"1","(1100,1100)","2","mstr_symbols","I44";
;
HDL_POWER"GND"
ROOM"DDR4_CH_C"
BODY_TYPE"PLUMBING"
CDS_LIB"mstr_symbols"
SIZE"1B"
BOM_COST"MEM"
VOLTAGE"0";
"A\NAC"21;
%"TAP"
"6","(-1700,4750)","2","mstr_standard","I46";
;
HDL_TAP"TRUE"
BODY_TYPE"PLUMBING"
CDS_LIB"mstr_standard";
"B \NAC \NWC"4;
"S \NAC"
BN"60"138;
%"TAP"
"6","(-1700,4700)","2","mstr_standard","I47";
;
HDL_TAP"TRUE"
BODY_TYPE"PLUMBING"
CDS_LIB"mstr_standard";
"B \NAC \NWC"4;
"S \NAC"
BN"61"140;
%"TAP"
"6","(-1700,4800)","2","mstr_standard","I48";
;
HDL_TAP"TRUE"
BODY_TYPE"PLUMBING"
CDS_LIB"mstr_standard";
"B \NAC \NWC"4;
"S \NAC"
BN"63"137;
%"TAP"
"6","(-1700,4850)","2","mstr_standard","I49";
;
HDL_TAP"TRUE"
BODY_TYPE"PLUMBING"
CDS_LIB"mstr_standard";
"B \NAC \NWC"4;
"S \NAC"
BN"62"136;
%"TAP"
"6","(900,5050)","2","mstr_standard","I5";
;
HDL_TAP"TRUE"
BODY_TYPE"PLUMBING"
CDS_LIB"mstr_standard";
"B \NAC \NWC"2;
"S \NAC"
BN"16"162;
%"TAP"
"6","(-1700,4450)","2","mstr_standard","I50";
;
HDL_TAP"TRUE"
BODY_TYPE"PLUMBING"
CDS_LIB"mstr_standard";
"B \NAC \NWC"4;
"S \NAC"
BN"54"132;
%"TAP"
"6","(-1700,4500)","2","mstr_standard","I51";
;
HDL_TAP"TRUE"
BODY_TYPE"PLUMBING"
CDS_LIB"mstr_standard";
"B \NAC \NWC"4;
"S \NAC"
BN"57"133;
%"TAP"
"6","(-1700,4600)","2","mstr_standard","I52";
;
HDL_TAP"TRUE"
BODY_TYPE"PLUMBING"
CDS_LIB"mstr_standard";
"B \NAC \NWC"4;
"S \NAC"
BN"59"130;
%"TAP"
"6","(-1700,4550)","2","mstr_standard","I53";
;
HDL_TAP"TRUE"
BODY_TYPE"PLUMBING"
CDS_LIB"mstr_standard";
"B \NAC \NWC"4;
"S \NAC"
BN"56"131;
%"TAP"
"6","(-1700,4650)","2","mstr_standard","I54";
;
HDL_TAP"TRUE"
BODY_TYPE"PLUMBING"
CDS_LIB"mstr_standard";
"B \NAC \NWC"4;
"S \NAC"
BN"58"139;
%"TAP"
"6","(-1700,4200)","2","mstr_standard","I55";
;
HDL_TAP"TRUE"
BODY_TYPE"PLUMBING"
CDS_LIB"mstr_standard";
"B \NAC \NWC"4;
"S \NAC"
BN"51"135;
%"TAP"
"6","(-1700,4250)","2","mstr_standard","I56";
;
HDL_TAP"TRUE"
BODY_TYPE"PLUMBING"
CDS_LIB"mstr_standard";
"B \NAC \NWC"4;
"S \NAC"
BN"50"134;
%"TAP"
"6","(-1700,4300)","2","mstr_standard","I57";
;
HDL_TAP"TRUE"
BODY_TYPE"PLUMBING"
CDS_LIB"mstr_standard";
"B \NAC \NWC"4;
"S \NAC"
BN"53"127;
%"TAP"
"6","(-1700,4400)","2","mstr_standard","I58";
;
HDL_TAP"TRUE"
BODY_TYPE"PLUMBING"
CDS_LIB"mstr_standard";
"B \NAC \NWC"4;
"S \NAC"
BN"55"129;
%"TAP"
"6","(-1700,4350)","2","mstr_standard","I59";
;
HDL_TAP"TRUE"
BODY_TYPE"PLUMBING"
CDS_LIB"mstr_standard";
"B \NAC \NWC"4;
"S \NAC"
BN"52"128;
%"TAP"
"6","(900,4950)","2","mstr_standard","I6";
;
HDL_TAP"TRUE"
BODY_TYPE"PLUMBING"
CDS_LIB"mstr_standard";
"B \NAC \NWC"2;
"S \NAC"
BN"15"164;
%"TAP"
"6","(-1700,3900)","2","mstr_standard","I60";
;
HDL_TAP"TRUE"
BODY_TYPE"PLUMBING"
CDS_LIB"mstr_standard";
"B \NAC \NWC"4;
"S \NAC"
BN"45"106;
%"TAP"
"6","(-1700,3950)","2","mstr_standard","I61";
;
HDL_TAP"TRUE"
BODY_TYPE"PLUMBING"
CDS_LIB"mstr_standard";
"B \NAC \NWC"4;
"S \NAC"
BN"44"107;
%"TAP"
"6","(-1700,4000)","2","mstr_standard","I62";
;
HDL_TAP"TRUE"
BODY_TYPE"PLUMBING"
CDS_LIB"mstr_standard";
"B \NAC \NWC"4;
"S \NAC"
BN"47"108;
%"TAP"
"6","(-1700,4100)","2","mstr_standard","I63";
;
HDL_TAP"TRUE"
BODY_TYPE"PLUMBING"
CDS_LIB"mstr_standard";
"B \NAC \NWC"4;
"S \NAC"
BN"49"125;
%"TAP"
"6","(-1700,4050)","2","mstr_standard","I64";
;
HDL_TAP"TRUE"
BODY_TYPE"PLUMBING"
CDS_LIB"mstr_standard";
"B \NAC \NWC"4;
"S \NAC"
BN"46"99;
%"TAP"
"6","(-1700,4150)","2","mstr_standard","I65";
;
HDL_TAP"TRUE"
BODY_TYPE"PLUMBING"
CDS_LIB"mstr_standard";
"B \NAC \NWC"4;
"S \NAC"
BN"48"126;
%"SCONN288_H44441004"
"2","(0,4350)","0","mstr_sconn","I66";
;
CDS_SEC"2"
ROOM"DDR4_CH_K"
CDS_LOCATION"J1B1"
SEC"2"
SEC_TYPE"PIP"
CDS_LIB"mstr_sconn"
BOM_COST"MEM"
PACK_TYPE"PIP"
MATERIAL"SCONN"
PART_NUMBER"H44441-004"
LOCATION"J1B1";
"DQS17P"
$PN"51"175;
"DQS9P"
$PN"7"154;
"DQS9N"
$PN"8"155;
"DQS8P"
$PN"197"156;
"DQS8N"
$PN"196"157;
"DQS7P"
$PN"278"158;
"DQS7N"
$PN"277"159;
"DQS6P"
$PN"267"160;
"DQS6N"
$PN"266"141;
"DQS5P"
$PN"256"142;
"DQS5N"
$PN"255"143;
"DQS4P"
$PN"245"144;
"DQS4N"
$PN"244"145;
"DQS3P"
$PN"186"146;
"DQS3N"
$PN"185"147;
"DQS2P"
$PN"175"148;
"DQS2N"
$PN"174"149;
"DQS1P"
$PN"164"150;
"DQS1N"
$PN"163"151;
"DQS17N"
$PN"52"176;
"DQS16P"
$PN"132"161;
"DQS16N"
$PN"133"162;
"DQS15P"
$PN"121"163;
"DQS15N"
$PN"122"164;
"DQS14P"
$PN"110"165;
"DQS14N"
$PN"111"166;
"DQS13P"
$PN"99"167;
"DQS13N"
$PN"100"168;
"DQS12P"
$PN"40"169;
"DQS12N"
$PN"41"170;
"DQS11P"
$PN"29"171;
"DQS11N"
$PN"30"172;
"DQS10P"
$PN"18"173;
"DQS10N"
$PN"19"174;
"DQS0P"
$PN"153"152;
"DQS0N"
$PN"152"153;
%"TAP"
"6","(-1700,3750)","2","mstr_standard","I67";
;
HDL_TAP"TRUE"
BODY_TYPE"PLUMBING"
CDS_LIB"mstr_standard";
"B \NAC \NWC"4;
"S \NAC"
BN"40"103;
%"TAP"
"6","(-1700,3650)","2","mstr_standard","I68";
;
HDL_TAP"TRUE"
BODY_TYPE"PLUMBING"
CDS_LIB"mstr_standard";
"B \NAC \NWC"4;
"S \NAC"
BN"38"101;
%"TAP"
"6","(-1700,3700)","2","mstr_standard","I69";
;
HDL_TAP"TRUE"
BODY_TYPE"PLUMBING"
CDS_LIB"mstr_standard";
"B \NAC \NWC"4;
"S \NAC"
BN"41"102;
%"TAP"
"6","(900,4850)","2","mstr_standard","I7";
;
HDL_TAP"TRUE"
BODY_TYPE"PLUMBING"
CDS_LIB"mstr_standard";
"B \NAC \NWC"2;
"S \NAC"
BN"14"166;
%"TAP"
"6","(-1700,3800)","2","mstr_standard","I70";
;
HDL_TAP"TRUE"
BODY_TYPE"PLUMBING"
CDS_LIB"mstr_standard";
"B \NAC \NWC"4;
"S \NAC"
BN"43"104;
%"TAP"
"6","(-1700,3850)","2","mstr_standard","I71";
;
HDL_TAP"TRUE"
BODY_TYPE"PLUMBING"
CDS_LIB"mstr_standard";
"B \NAC \NWC"4;
"S \NAC"
BN"42"105;
%"TAP"
"6","(-1700,3450)","2","mstr_standard","I72";
;
HDL_TAP"TRUE"
BODY_TYPE"PLUMBING"
CDS_LIB"mstr_standard";
"B \NAC \NWC"4;
"S \NAC"
BN"34"90;
%"TAP"
"6","(-1700,3400)","2","mstr_standard","I73";
;
HDL_TAP"TRUE"
BODY_TYPE"PLUMBING"
CDS_LIB"mstr_standard";
"B \NAC \NWC"4;
"S \NAC"
BN"35"95;
%"TAP"
"6","(-1700,3500)","2","mstr_standard","I74";
;
HDL_TAP"TRUE"
BODY_TYPE"PLUMBING"
CDS_LIB"mstr_standard";
"B \NAC \NWC"4;
"S \NAC"
BN"37"89;
%"TAP"
"6","(-1700,3550)","2","mstr_standard","I75";
;
HDL_TAP"TRUE"
BODY_TYPE"PLUMBING"
CDS_LIB"mstr_standard";
"B \NAC \NWC"4;
"S \NAC"
BN"36"96;
%"TAP"
"6","(-1700,3600)","2","mstr_standard","I76";
;
HDL_TAP"TRUE"
BODY_TYPE"PLUMBING"
CDS_LIB"mstr_standard";
"B \NAC \NWC"4;
"S \NAC"
BN"39"100;
%"TAP"
"6","(-1700,3200)","2","mstr_standard","I77";
;
HDL_TAP"TRUE"
BODY_TYPE"PLUMBING"
CDS_LIB"mstr_standard";
"B \NAC \NWC"4;
"S \NAC"
BN"31"91;
%"TAP"
"6","(-1700,3250)","2","mstr_standard","I78";
;
HDL_TAP"TRUE"
BODY_TYPE"PLUMBING"
CDS_LIB"mstr_standard";
"B \NAC \NWC"4;
"S \NAC"
BN"30"92;
%"TAP"
"6","(-1700,3150)","2","mstr_standard","I79";
;
HDL_TAP"TRUE"
BODY_TYPE"PLUMBING"
CDS_LIB"mstr_standard";
"B \NAC \NWC"4;
"S \NAC"
BN"28"98;
%"TAP"
"6","(900,4750)","2","mstr_standard","I8";
;
HDL_TAP"TRUE"
BODY_TYPE"PLUMBING"
CDS_LIB"mstr_standard";
"B \NAC \NWC"2;
"S \NAC"
BN"13"168;
%"TAP"
"6","(-1700,3300)","2","mstr_standard","I80";
;
HDL_TAP"TRUE"
BODY_TYPE"PLUMBING"
CDS_LIB"mstr_standard";
"B \NAC \NWC"4;
"S \NAC"
BN"33"93;
%"TAP"
"6","(-1700,3350)","2","mstr_standard","I81";
;
HDL_TAP"TRUE"
BODY_TYPE"PLUMBING"
CDS_LIB"mstr_standard";
"B \NAC \NWC"4;
"S \NAC"
BN"32"94;
%"TAP"
"6","(-1700,2950)","2","mstr_standard","I82";
;
HDL_TAP"TRUE"
BODY_TYPE"PLUMBING"
CDS_LIB"mstr_standard";
"B \NAC \NWC"4;
"S \NAC"
BN"24"87;
%"TAP"
"6","(-1700,2900)","2","mstr_standard","I83";
;
HDL_TAP"TRUE"
BODY_TYPE"PLUMBING"
CDS_LIB"mstr_standard";
"B \NAC \NWC"4;
"S \NAC"
BN"25"86;
%"TAP"
"6","(-1700,3000)","2","mstr_standard","I84";
;
HDL_TAP"TRUE"
BODY_TYPE"PLUMBING"
CDS_LIB"mstr_standard";
"B \NAC \NWC"4;
"S \NAC"
BN"27"79;
%"TAP"
"6","(-1700,3100)","2","mstr_standard","I85";
;
HDL_TAP"TRUE"
BODY_TYPE"PLUMBING"
CDS_LIB"mstr_standard";
"B \NAC \NWC"4;
"S \NAC"
BN"29"97;
%"TAP"
"6","(-1700,3050)","2","mstr_standard","I86";
;
HDL_TAP"TRUE"
BODY_TYPE"PLUMBING"
CDS_LIB"mstr_standard";
"B \NAC \NWC"4;
"S \NAC"
BN"26"80;
%"TAP"
"6","(-1700,2650)","2","mstr_standard","I87";
;
HDL_TAP"TRUE"
BODY_TYPE"PLUMBING"
CDS_LIB"mstr_standard";
"B \NAC \NWC"4;
"S \NAC"
BN"18"82;
%"TAP"
"6","(-1700,2700)","2","mstr_standard","I88";
;
HDL_TAP"TRUE"
BODY_TYPE"PLUMBING"
CDS_LIB"mstr_standard";
"B \NAC \NWC"4;
"S \NAC"
BN"21"83;
%"TAP"
"6","(-1700,2750)","2","mstr_standard","I89";
;
HDL_TAP"TRUE"
BODY_TYPE"PLUMBING"
CDS_LIB"mstr_standard";
"B \NAC \NWC"4;
"S \NAC"
BN"20"84;
%"TAP"
"6","(900,4650)","2","mstr_standard","I9";
;
HDL_TAP"TRUE"
BODY_TYPE"PLUMBING"
CDS_LIB"mstr_standard";
"B \NAC \NWC"2;
"S \NAC"
BN"12"170;
%"TAP"
"6","(-1700,2850)","2","mstr_standard","I90";
;
HDL_TAP"TRUE"
BODY_TYPE"PLUMBING"
CDS_LIB"mstr_standard";
"B \NAC \NWC"4;
"S \NAC"
BN"22"85;
%"TAP"
"6","(-1700,2800)","2","mstr_standard","I91";
;
HDL_TAP"TRUE"
BODY_TYPE"PLUMBING"
CDS_LIB"mstr_standard";
"B \NAC \NWC"4;
"S \NAC"
BN"23"88;
%"TAP"
"6","(-1700,2400)","2","mstr_standard","I92";
;
HDL_TAP"TRUE"
BODY_TYPE"PLUMBING"
CDS_LIB"mstr_standard";
"B \NAC \NWC"4;
"S \NAC"
BN"15"77;
%"TAP"
"6","(-1700,2450)","2","mstr_standard","I93";
;
HDL_TAP"TRUE"
BODY_TYPE"PLUMBING"
CDS_LIB"mstr_standard";
"B \NAC \NWC"4;
"S \NAC"
BN"14"69;
%"TAP"
"6","(-1700,2550)","2","mstr_standard","I94";
;
HDL_TAP"TRUE"
BODY_TYPE"PLUMBING"
CDS_LIB"mstr_standard";
"B \NAC \NWC"4;
"S \NAC"
BN"16"68;
%"TAP"
"6","(-1700,2500)","2","mstr_standard","I95";
;
HDL_TAP"TRUE"
BODY_TYPE"PLUMBING"
CDS_LIB"mstr_standard";
"B \NAC \NWC"4;
"S \NAC"
BN"17"78;
%"TAP"
"6","(-1700,2600)","2","mstr_standard","I96";
;
HDL_TAP"TRUE"
BODY_TYPE"PLUMBING"
CDS_LIB"mstr_standard";
"B \NAC \NWC"4;
"S \NAC"
BN"19"81;
%"TAP"
"6","(-1700,2350)","2","mstr_standard","I97";
;
HDL_TAP"TRUE"
BODY_TYPE"PLUMBING"
CDS_LIB"mstr_standard";
"B \NAC \NWC"4;
"S \NAC"
BN"12"76;
%"TAP"
"6","(-1700,2250)","2","mstr_standard","I98";
;
HDL_TAP"TRUE"
BODY_TYPE"PLUMBING"
CDS_LIB"mstr_standard";
"B \NAC \NWC"4;
"S \NAC"
BN"10"74;
%"TAP"
"6","(-1700,2300)","2","mstr_standard","I99";
;
HDL_TAP"TRUE"
BODY_TYPE"PLUMBING"
CDS_LIB"mstr_standard";
"B \NAC \NWC"4;
"S \NAC"
BN"13"75;
END.
